(kicad_pcb
	(version 20260206)
	(generator "pcbnew")
	(generator_version "10.0")
	(general
		(thickness 1.6)
		(legacy_teardrops no)
	)
	(paper "A4")
	(title_block
		(title "netronome-mezz — pcbd0082-001_rev01_jul9_a.brd")
		(comment 1 "Open CloudServer (Microsoft) / footprints 95-103 of 714")
	)
	(layers
		(0 "F.Cu" signal "TOP")
		(4 "In1.Cu" signal "02_GND")
		(6 "In2.Cu" signal "03_SIG")
		(8 "In3.Cu" signal "04_SIG")
		(10 "In4.Cu" signal "05_GND")
		(12 "In5.Cu" signal "06_PWR1")
		(14 "In6.Cu" signal "07_SIG")
		(16 "In7.Cu" signal "08_SIG")
		(18 "In8.Cu" signal "09_GND")
		(2 "B.Cu" signal "BOTTOM")
		(9 "F.Adhes" user "F.Adhesive")
		(11 "B.Adhes" user "B.Adhesive")
		(13 "F.Paste" user "Package Geometry/Pastemask Top")
		(15 "B.Paste" user "Package Geometry/Pastemask Bottom")
		(5 "F.SilkS" user "Ref Des/Silkscreen Top")
		(7 "B.SilkS" user "Ref Des/Silkscreen Bottom")
		(1 "F.Mask" user "Board Geometry/Soldermask Top")
		(3 "B.Mask" user "Board Geometry/Soldermask Bottom")
		(17 "Dwgs.User" user "User.Drawings")
		(19 "Cmts.User" user "User.Comments")
		(21 "Eco1.User" user "User.Eco1")
		(23 "Eco2.User" user "User.Eco2")
		(25 "Edge.Cuts" user "Board Geometry/Outline")
		(27 "Margin" user)
		(31 "F.CrtYd" user "Package Geometry/Place Bound Top")
		(29 "B.CrtYd" user "Package Geometry/Place Bound Bottom")
		(35 "F.Fab" user "Ref Des/Assembly Top")
		(33 "B.Fab" user "Ref Des/Assembly Bottom")
		(45 "User.4" user "COMPVAL_TYPE_BOTTOM")
	)
	(footprint ""
		(layer "F.Cu")
		(at 29.21 32.639 180)
		(property "Reference" "R93"
			(at 0 0 180)
			(layer "F.SilkS")
			(hide yes)
			(effects
				(font
					(size 1.27 1.27)
				)
			)
		)
		(property "Value" "4.75K"
			(at -0.148158 1.3462 270)
			(unlocked yes)
			(layer "F.Fab")
			(hide yes)
			(effects
				(font
					(size 1.27 0.9652)
					(thickness 0.000001)
				)
				(justify left)
			)
		)
		(property "Device Type" "REST4024"
			(at -0.148158 1.3462 270)
			(unlocked yes)
			(layer "F.Fab")
			(hide yes)
			(effects
				(font
					(size 1.27 0.9652)
					(thickness 0.000001)
				)
				(justify left)
			)
		)
		(duplicate_pad_numbers_are_jumpers no)
		(fp_poly
			(pts
				(xy 0.635 1.0668) (xy 0.635 -1.0668) (xy -0.635 -1.0668) (xy -0.635 1.0668)
			)
			(stroke
				(width 0)
				(type default)
			)
			(fill no)
			(layer "F.CrtYd")
		)
		(fp_line
			(start 0.254 0.508)
			(end -0.254 0.508)
			(stroke
				(width 0.0254)
				(type default)
			)
			(layer "F.Fab")
		)
		(fp_line
			(start 0.254 -0.508)
			(end 0.254 0.508)
			(stroke
				(width 0.0254)
				(type default)
			)
			(layer "F.Fab")
		)
		(fp_line
			(start -0.254 0.508)
			(end -0.254 -0.508)
			(stroke
				(width 0.0254)
				(type default)
			)
			(layer "F.Fab")
		)
		(fp_line
			(start -0.254 -0.508)
			(end 0.254 -0.508)
			(stroke
				(width 0.0254)
				(type default)
			)
			(layer "F.Fab")
		)
		(pad "1" smd rect
			(at 0 -0.4191 180)
			(size 0.508 0.5334)
			(layers "F.Cu" "F.Mask" "F.Paste")
			(net "_NFP_CORE_VID2")
		)
		(pad "2" smd rect
			(at 0 0.4191 180)
			(size 0.508 0.5334)
			(layers "F.Cu" "F.Mask" "F.Paste")
			(net "VDD_1.2V")
		)
		(zone
			(layer "F.Cu")
			(hatch none 0.5)
			(connect_pads
				(clearance 0)
			)
			(min_thickness 0.25)
			(keepout
				(tracks not_allowed)
				(vias allowed)
				(pads allowed)
				(copperpour not_allowed)
				(footprints allowed)
			)
			(placement
				(enabled no)
				(sheetname "")
			)
			(fill
				(thermal_gap 0.5)
				(thermal_bridge_width 0.5)
				(island_removal_mode 0)
			)
			(polygon
				(pts
					(xy 29.1846 32.6644) (xy 29.1846 32.6136) (xy 29.2354 32.6136) (xy 29.2354 32.6644)
				)
			)
		)
	)
	(footprint ""
		(layer "F.Cu")
		(at 73.152 28.194 180)
		(property "Reference" "R339"
			(at 0.86233 -1.27 90)
			(unlocked yes)
			(layer "F.SilkS")
			(effects
				(font
					(size 0.7874 0.5842)
					(thickness 0.127)
				)
				(justify left)
			)
		)
		(property "Value" "4.75K"
			(at -0.148158 1.3462 270)
			(unlocked yes)
			(layer "F.Fab")
			(hide yes)
			(effects
				(font
					(size 1.27 0.9652)
					(thickness 0.000001)
				)
				(justify left)
			)
		)
		(property "Device Type" "REST4024"
			(at -0.148158 1.3462 270)
			(unlocked yes)
			(layer "F.Fab")
			(hide yes)
			(effects
				(font
					(size 1.27 0.9652)
					(thickness 0.000001)
				)
				(justify left)
			)
		)
		(duplicate_pad_numbers_are_jumpers no)
		(fp_poly
			(pts
				(xy 0.635 1.0668) (xy 0.635 -1.0668) (xy -0.635 -1.0668) (xy -0.635 1.0668)
			)
			(stroke
				(width 0)
				(type default)
			)
			(fill no)
			(layer "F.CrtYd")
		)
		(fp_line
			(start 0.254 0.508)
			(end -0.254 0.508)
			(stroke
				(width 0.0254)
				(type default)
			)
			(layer "F.Fab")
		)
		(fp_line
			(start 0.254 -0.508)
			(end 0.254 0.508)
			(stroke
				(width 0.0254)
				(type default)
			)
			(layer "F.Fab")
		)
		(fp_line
			(start -0.254 0.508)
			(end -0.254 -0.508)
			(stroke
				(width 0.0254)
				(type default)
			)
			(layer "F.Fab")
		)
		(fp_line
			(start -0.254 -0.508)
			(end 0.254 -0.508)
			(stroke
				(width 0.0254)
				(type default)
			)
			(layer "F.Fab")
		)
		(pad "1" smd rect
			(at 0 -0.4191 180)
			(size 0.508 0.5334)
			(layers "F.Cu" "F.Mask" "F.Paste")
			(net "GND")
		)
		(pad "2" smd rect
			(at 0 0.4191 180)
			(size 0.508 0.5334)
			(layers "F.Cu" "F.Mask" "F.Paste")
			(net "12N3294")
		)
		(zone
			(layer "F.Cu")
			(hatch none 0.5)
			(connect_pads
				(clearance 0)
			)
			(min_thickness 0.25)
			(keepout
				(tracks not_allowed)
				(vias allowed)
				(pads allowed)
				(copperpour not_allowed)
				(footprints allowed)
			)
			(placement
				(enabled no)
				(sheetname "")
			)
			(fill
				(thermal_gap 0.5)
				(thermal_bridge_width 0.5)
				(island_removal_mode 0)
			)
			(polygon
				(pts
					(xy 73.1266 28.2194) (xy 73.1266 28.1686) (xy 73.1774 28.1686) (xy 73.1774 28.2194)
				)
			)
		)
	)
	(footprint ""
		(layer "F.Cu")
		(at 19.431 47.498)
		(property "Reference" "TP43"
			(at -1.397 2.05867 0)
			(unlocked yes)
			(layer "F.SilkS")
			(effects
				(font
					(size 0.7874 0.5842)
					(thickness 0.127)
				)
				(justify left)
			)
		)
		(property "Value" "*"
			(at -0.4826 -0.14732 0)
			(unlocked yes)
			(layer "F.Fab")
			(hide yes)
			(effects
				(font
					(size 1.27 0.9652)
					(thickness 0.000001)
				)
				(justify left)
			)
		)
		(property "Device Type" "TP_SMALL"
			(at -0.4826 -0.14732 0)
			(unlocked yes)
			(layer "F.Fab")
			(hide yes)
			(effects
				(font
					(size 1.27 0.9652)
					(thickness 0.000001)
				)
				(justify left)
			)
		)
		(duplicate_pad_numbers_are_jumpers no)
		(fp_line
			(start -0.8636 -0.8636)
			(end -0.8636 0.8636)
			(stroke
				(width 0.1524)
				(type default)
			)
			(layer "F.SilkS")
		)
		(fp_line
			(start -0.8636 0.8636)
			(end 0.8636 0.8636)
			(stroke
				(width 0.1524)
				(type default)
			)
			(layer "F.SilkS")
		)
		(fp_line
			(start 0.8636 -0.8636)
			(end -0.8636 -0.8636)
			(stroke
				(width 0.1524)
				(type default)
			)
			(layer "F.SilkS")
		)
		(fp_line
			(start 0.8636 0.8636)
			(end 0.8636 -0.8636)
			(stroke
				(width 0.1524)
				(type default)
			)
			(layer "F.SilkS")
		)
		(fp_poly
			(pts
				(xy -0.635 -0.635) (xy -0.635 0.635) (xy 0.635 0.635) (xy 0.635 -0.635)
			)
			(stroke
				(width 0)
				(type default)
			)
			(fill no)
			(layer "F.CrtYd")
		)
		(pad "1" smd rect
			(at 0 0)
			(size 1.27 1.27)
			(layers "F.Cu" "F.Mask" "F.Paste")
			(net "GND")
		)
	)
	(footprint ""
		(layer "F.Cu")
		(at 80.645 9.398 -90)
		(property "Reference" "C211"
			(at 0.78867 1.905 0)
			(unlocked yes)
			(layer "F.SilkS")
			(effects
				(font
					(size 0.7874 0.5842)
					(thickness 0.127)
				)
				(justify left)
			)
		)
		(property "Value" "1UF"
			(at -0.091846 0.2921 0)
			(unlocked yes)
			(layer "F.Fab")
			(hide yes)
			(effects
				(font
					(size 0.7874 0.5842)
					(thickness 0.2032)
				)
				(justify left)
			)
		)
		(property "Device Type" "CAPC0028"
			(at -0.091846 0.2921 0)
			(unlocked yes)
			(layer "F.Fab")
			(hide yes)
			(effects
				(font
					(size 0.7874 0.5842)
					(thickness 0.2032)
				)
				(justify left)
			)
		)
		(duplicate_pad_numbers_are_jumpers no)
		(fp_poly
			(pts
				(xy 0.635 1.0668) (xy 0.635 -1.0668) (xy -0.635 -1.0668) (xy -0.635 1.0668)
			)
			(stroke
				(width 0)
				(type default)
			)
			(fill no)
			(layer "F.CrtYd")
		)
		(fp_line
			(start -0.254 0.508)
			(end -0.254 -0.508)
			(stroke
				(width 0.0254)
				(type default)
			)
			(layer "F.Fab")
		)
		(fp_line
			(start 0.254 0.508)
			(end -0.254 0.508)
			(stroke
				(width 0.0254)
				(type default)
			)
			(layer "F.Fab")
		)
		(fp_line
			(start -0.254 -0.508)
			(end 0.254 -0.508)
			(stroke
				(width 0.0254)
				(type default)
			)
			(layer "F.Fab")
		)
		(fp_line
			(start 0.254 -0.508)
			(end 0.254 0.508)
			(stroke
				(width 0.0254)
				(type default)
			)
			(layer "F.Fab")
		)
		(pad "1" smd rect
			(at 0 -0.4191 270)
			(size 0.508 0.5334)
			(layers "F.Cu" "F.Mask" "F.Paste")
			(net "DDR_VDDQ")
		)
		(pad "2" smd rect
			(at 0 0.4191 270)
			(size 0.508 0.5334)
			(layers "F.Cu" "F.Mask" "F.Paste")
			(net "GND")
		)
		(zone
			(layer "F.Cu")
			(hatch none 0.5)
			(connect_pads
				(clearance 0)
			)
			(min_thickness 0.25)
			(keepout
				(tracks not_allowed)
				(vias allowed)
				(pads allowed)
				(copperpour not_allowed)
				(footprints allowed)
			)
			(placement
				(enabled no)
				(sheetname "")
			)
			(fill
				(thermal_gap 0.5)
				(thermal_bridge_width 0.5)
				(island_removal_mode 0)
			)
			(polygon
				(pts
					(xy 80.6704 9.4234) (xy 80.6196 9.4234) (xy 80.6196 9.3726) (xy 80.6704 9.3726)
				)
			)
		)
	)
	(footprint ""
		(layer "F.Cu")
		(at 13.208 28.702)
		(property "Reference" "TP41"
			(at -2.032 -2.00533 0)
			(unlocked yes)
			(layer "F.SilkS")
			(effects
				(font
					(size 0.7874 0.5842)
					(thickness 0.127)
				)
				(justify left)
			)
		)
		(property "Value" "*"
			(at -0.4826 -0.14732 0)
			(unlocked yes)
			(layer "F.Fab")
			(hide yes)
			(effects
				(font
					(size 1.27 0.9652)
					(thickness 0.000001)
				)
				(justify left)
			)
		)
		(property "Device Type" "TP_SMALL"
			(at -0.4826 -0.14732 0)
			(unlocked yes)
			(layer "F.Fab")
			(hide yes)
			(effects
				(font
					(size 1.27 0.9652)
					(thickness 0.000001)
				)
				(justify left)
			)
		)
		(duplicate_pad_numbers_are_jumpers no)
		(fp_line
			(start -0.8636 -0.8636)
			(end -0.8636 0.8636)
			(stroke
				(width 0.1524)
				(type default)
			)
			(layer "F.SilkS")
		)
		(fp_line
			(start -0.8636 0.8636)
			(end 0.8636 0.8636)
			(stroke
				(width 0.1524)
				(type default)
			)
			(layer "F.SilkS")
		)
		(fp_line
			(start 0.8636 -0.8636)
			(end -0.8636 -0.8636)
			(stroke
				(width 0.1524)
				(type default)
			)
			(layer "F.SilkS")
		)
		(fp_line
			(start 0.8636 0.8636)
			(end 0.8636 -0.8636)
			(stroke
				(width 0.1524)
				(type default)
			)
			(layer "F.SilkS")
		)
		(fp_poly
			(pts
				(xy -0.635 -0.635) (xy -0.635 0.635) (xy 0.635 0.635) (xy 0.635 -0.635)
			)
			(stroke
				(width 0)
				(type default)
			)
			(fill no)
			(layer "F.CrtYd")
		)
		(pad "1" smd rect
			(at 0 0)
			(size 1.27 1.27)
			(layers "F.Cu" "F.Mask" "F.Paste")
			(net "GND")
		)
	)
	(footprint ""
		(layer "F.Cu")
		(at 8.5852 38.735)
		(property "Reference" "TP21"
			(at 0.15367 -0.889 90)
			(unlocked yes)
			(layer "F.SilkS")
			(effects
				(font
					(size 0.7874 0.5842)
					(thickness 0.127)
				)
				(justify left)
			)
		)
		(property "Value" "*"
			(at -0.4826 -0.14732 0)
			(unlocked yes)
			(layer "F.Fab")
			(hide yes)
			(effects
				(font
					(size 1.27 0.9652)
					(thickness 0.000001)
				)
				(justify left)
			)
		)
		(property "Device Type" "TP_SMALL"
			(at -0.4826 -0.14732 0)
			(unlocked yes)
			(layer "F.Fab")
			(hide yes)
			(effects
				(font
					(size 1.27 0.9652)
					(thickness 0.000001)
				)
				(justify left)
			)
		)
		(duplicate_pad_numbers_are_jumpers no)
		(fp_line
			(start -0.8636 -0.8636)
			(end -0.8636 0.8636)
			(stroke
				(width 0.1524)
				(type default)
			)
			(layer "F.SilkS")
		)
		(fp_line
			(start -0.8636 0.8636)
			(end 0.8636 0.8636)
			(stroke
				(width 0.1524)
				(type default)
			)
			(layer "F.SilkS")
		)
		(fp_line
			(start 0.8636 -0.8636)
			(end -0.8636 -0.8636)
			(stroke
				(width 0.1524)
				(type default)
			)
			(layer "F.SilkS")
		)
		(fp_line
			(start 0.8636 0.8636)
			(end 0.8636 -0.8636)
			(stroke
				(width 0.1524)
				(type default)
			)
			(layer "F.SilkS")
		)
		(fp_poly
			(pts
				(xy -0.635 -0.635) (xy -0.635 0.635) (xy 0.635 0.635) (xy 0.635 -0.635)
			)
			(stroke
				(width 0)
				(type default)
			)
			(fill no)
			(layer "F.CrtYd")
		)
		(pad "1" smd rect
			(at 0 0)
			(size 1.27 1.27)
			(layers "F.Cu" "F.Mask" "F.Paste")
			(net "CPLD_GPIO_1")
		)
	)
	(footprint ""
		(layer "F.Cu")
		(at 66.802 36.957 90)
		(property "Reference" "R171"
			(at 0.86233 -0.127 0)
			(unlocked yes)
			(layer "F.SilkS")
			(effects
				(font
					(size 0.7874 0.5842)
					(thickness 0.127)
				)
				(justify left)
			)
		)
		(property "Value" "0"
			(at -0.148158 1.3462 180)
			(unlocked yes)
			(layer "F.Fab")
			(hide yes)
			(effects
				(font
					(size 1.27 0.9652)
					(thickness 0.000001)
				)
				(justify left)
			)
		)
		(property "Device Type" "REST1111"
			(at -0.148158 1.3462 180)
			(unlocked yes)
			(layer "F.Fab")
			(hide yes)
			(effects
				(font
					(size 1.27 0.9652)
					(thickness 0.000001)
				)
				(justify left)
			)
		)
		(duplicate_pad_numbers_are_jumpers no)
		(fp_poly
			(pts
				(xy 0.635 1.0668) (xy 0.635 -1.0668) (xy -0.635 -1.0668) (xy -0.635 1.0668)
			)
			(stroke
				(width 0)
				(type default)
			)
			(fill no)
			(layer "F.CrtYd")
		)
		(fp_line
			(start 0.254 -0.508)
			(end 0.254 0.508)
			(stroke
				(width 0.0254)
				(type default)
			)
			(layer "F.Fab")
		)
		(fp_line
			(start -0.254 -0.508)
			(end 0.254 -0.508)
			(stroke
				(width 0.0254)
				(type default)
			)
			(layer "F.Fab")
		)
		(fp_line
			(start 0.254 0.508)
			(end -0.254 0.508)
			(stroke
				(width 0.0254)
				(type default)
			)
			(layer "F.Fab")
		)
		(fp_line
			(start -0.254 0.508)
			(end -0.254 -0.508)
			(stroke
				(width 0.0254)
				(type default)
			)
			(layer "F.Fab")
		)
		(pad "1" smd rect
			(at 0 -0.4191 90)
			(size 0.508 0.5334)
			(layers "F.Cu" "F.Mask" "F.Paste")
			(net "L_1_CORE_PHASE")
		)
		(pad "2" smd rect
			(at 0 0.4191 90)
			(size 0.508 0.5334)
			(layers "F.Cu" "F.Mask" "F.Paste")
			(net "NFP_VDD_CORE_ISEN1_P")
		)
		(zone
			(layer "F.Cu")
			(hatch none 0.5)
			(connect_pads
				(clearance 0)
			)
			(min_thickness 0.25)
			(keepout
				(tracks not_allowed)
				(vias allowed)
				(pads allowed)
				(copperpour not_allowed)
				(footprints allowed)
			)
			(placement
				(enabled no)
				(sheetname "")
			)
			(fill
				(thermal_gap 0.5)
				(thermal_bridge_width 0.5)
				(island_removal_mode 0)
			)
			(polygon
				(pts
					(xy 66.7766 36.9316) (xy 66.8274 36.9316) (xy 66.8274 36.9824) (xy 66.7766 36.9824)
				)
			)
		)
	)
	(footprint ""
		(layer "F.Cu")
		(at 35.941 9.779 90)
		(property "Reference" "R135"
			(at 0 0 90)
			(layer "F.SilkS")
			(hide yes)
			(effects
				(font
					(size 1.27 1.27)
				)
			)
		)
		(property "Value" "0"
			(at -0.148158 1.3462 180)
			(unlocked yes)
			(layer "F.Fab")
			(hide yes)
			(effects
				(font
					(size 1.27 0.9652)
					(thickness 0.000001)
				)
				(justify left)
			)
		)
		(property "Device Type" "REST1111"
			(at -0.148158 1.3462 180)
			(unlocked yes)
			(layer "F.Fab")
			(hide yes)
			(effects
				(font
					(size 1.27 0.9652)
					(thickness 0.000001)
				)
				(justify left)
			)
		)
		(duplicate_pad_numbers_are_jumpers no)
		(fp_poly
			(pts
				(xy 0.635 1.0668) (xy 0.635 -1.0668) (xy -0.635 -1.0668) (xy -0.635 1.0668)
			)
			(stroke
				(width 0)
				(type default)
			)
			(fill no)
			(layer "F.CrtYd")
		)
		(fp_line
			(start 0.254 -0.508)
			(end 0.254 0.508)
			(stroke
				(width 0.0254)
				(type default)
			)
			(layer "F.Fab")
		)
		(fp_line
			(start -0.254 -0.508)
			(end 0.254 -0.508)
			(stroke
				(width 0.0254)
				(type default)
			)
			(layer "F.Fab")
		)
		(fp_line
			(start 0.254 0.508)
			(end -0.254 0.508)
			(stroke
				(width 0.0254)
				(type default)
			)
			(layer "F.Fab")
		)
		(fp_line
			(start -0.254 0.508)
			(end -0.254 -0.508)
			(stroke
				(width 0.0254)
				(type default)
			)
			(layer "F.Fab")
		)
		(pad "1" smd rect
			(at 0 -0.4191 90)
			(size 0.508 0.5334)
			(layers "F.Cu" "F.Mask" "F.Paste")
			(net "3N2301")
		)
		(pad "2" smd rect
			(at 0 0.4191 90)
			(size 0.508 0.5334)
			(layers "F.Cu" "F.Mask" "F.Paste")
			(net "NFP_CLK_REF_N")
		)
		(zone
			(layer "F.Cu")
			(hatch none 0.5)
			(connect_pads
				(clearance 0)
			)
			(min_thickness 0.25)
			(keepout
				(tracks not_allowed)
				(vias allowed)
				(pads allowed)
				(copperpour not_allowed)
				(footprints allowed)
			)
			(placement
				(enabled no)
				(sheetname "")
			)
			(fill
				(thermal_gap 0.5)
				(thermal_bridge_width 0.5)
				(island_removal_mode 0)
			)
			(polygon
				(pts
					(xy 35.9156 9.7536) (xy 35.9664 9.7536) (xy 35.9664 9.8044) (xy 35.9156 9.8044)
				)
			)
		)
	)
	(footprint ""
		(layer "F.Cu")
		(at 6.985 33.02 90)
		(property "Reference" "L10"
			(at 2.51333 -0.508 0)
			(unlocked yes)
			(layer "F.SilkS")
			(effects
				(font
					(size 0.7874 0.5842)
					(thickness 0.127)
				)
				(justify left)
			)
		)
		(property "Value" "2.2UH"
			(at -0.483362 -0.148082 90)
			(unlocked yes)
			(layer "F.Fab")
			(hide yes)
			(effects
				(font
					(size 1.27 0.9652)
					(thickness 0.000001)
				)
				(justify left)
			)
		)
		(property "Device Type" "INDS0060"
			(at -0.483362 -0.148082 90)
			(unlocked yes)
			(layer "F.Fab")
			(hide yes)
			(effects
				(font
					(size 1.27 0.9652)
					(thickness 0.000001)
				)
				(justify left)
			)
		)
		(duplicate_pad_numbers_are_jumpers no)
		(fp_line
			(start -1.27 -1.397)
			(end 1.27 -1.397)
			(stroke
				(width 0.1524)
				(type default)
			)
			(layer "F.SilkS")
		)
		(fp_line
			(start 1.27 1.397)
			(end -1.27 1.397)
			(stroke
				(width 0.1524)
				(type default)
			)
			(layer "F.SilkS")
		)
		(fp_poly
			(pts
				(xy 2.159 -1.651) (xy 2.159 1.651) (xy -2.159 1.651) (xy -2.159 -1.651)
			)
			(stroke
				(width 0)
				(type default)
			)
			(fill no)
			(layer "F.CrtYd")
		)
		(fp_line
			(start 1.3462 -1.1049)
			(end -1.3462 -1.1049)
			(stroke
				(width 0.1524)
				(type default)
			)
			(layer "F.Fab")
		)
		(fp_line
			(start -1.3462 -1.1049)
			(end -1.3462 1.1049)
			(stroke
				(width 0.1524)
				(type default)
			)
			(layer "F.Fab")
		)
		(fp_line
			(start 1.3462 1.1049)
			(end 1.3462 -1.1049)
			(stroke
				(width 0.1524)
				(type default)
			)
			(layer "F.Fab")
		)
		(fp_line
			(start -1.3462 1.1049)
			(end 1.3462 1.1049)
			(stroke
				(width 0.1524)
				(type default)
			)
			(layer "F.Fab")
		)
		(pad "1" smd rect
			(at -1.1303 0 90)
			(size 1.1938 2.3368)
			(layers "F.Cu" "F.Mask" "F.Paste")
			(net "VDD_1.2V")
		)
		(pad "2" smd rect
			(at 1.1303 0 90)
			(size 1.1938 2.3368)
			(layers "F.Cu" "F.Mask" "F.Paste")
			(net "11N1970")
		)
		(zone
			(layer "F.Cu")
			(hatch none 0.5)
			(connect_pads
				(clearance 0)
			)
			(min_thickness 0.25)
			(keepout
				(tracks allowed)
				(vias not_allowed)
				(pads allowed)
				(copperpour not_allowed)
				(footprints allowed)
			)
			(placement
				(enabled no)
				(sheetname "")
			)
			(fill
				(thermal_gap 0.5)
				(thermal_bridge_width 0.5)
				(island_removal_mode 0)
			)
			(polygon
				(pts
					(xy 8.0899 34.3662) (xy 8.0899 31.6738) (xy 5.8801 31.6738) (xy 5.8801 34.3662)
				)
			)
		)
	)
)
